# T6G (Grand Teton) — schematic netlist excerpt (pin names and nets, part order shuffled) for the footprints in the layout excerpt that follows; sources: Cadence DE-HDL packaged netlist, KiCad conversion of 04192023_DAF0TMB3IC0_F0TG_MB_C_brd_V02_OCP.brd

C7  Q_CAP  0.1UF 25V 10% X7R  pkg 0402  page 124 : A = GPU_3V3IO_RSVD3_ISO ; B = GND
C6097  Q_CAP  0.01UF 50V 10% X7R  pkg C0402  page 179 : A = P3V3_AUX_CPU0_USB2_AVDD33 ; B = GND
C6733  Q_CAP_DIFFBUS  DIFF BUS_0.22UF 6.3V 20% X6S  pkg C0201  page 352 : \1\ = P5E_CPU1_P3_TX_BUF_C_DP<4> ; \2\ = P5E_CPU1_P3_TX_BUF_DP<4>

(kicad_pcb
	(version 20260206)
	(generator "pcbnew")
	(generator_version "10.0")
	(general
		(thickness 1.6)
		(legacy_teardrops no)
	)
	(paper "A4")
	(title_block
		(title "04192023_DAF0TMB3IC0_F0TG_MB_C_brd_V02_OCP.brd")
		(comment 1 "Grand Teton / footprints 7582-7584 of 8354")
	)
	(layers
		(0 "F.Cu" signal "TOP")
		(4 "In1.Cu" signal "GND")
		(6 "In2.Cu" signal "IN1")
		(8 "In3.Cu" signal "GND1")
		(10 "In4.Cu" signal "IN2")
		(12 "In5.Cu" signal "GND2")
		(14 "In6.Cu" signal "IN3")
		(16 "In7.Cu" signal "GND3")
		(18 "In8.Cu" signal "VCC")
		(20 "In9.Cu" signal "VCC1")
		(22 "In10.Cu" signal "GND4")
		(24 "In11.Cu" signal "IN4")
		(26 "In12.Cu" signal "GND5")
		(28 "In13.Cu" signal "IN5")
		(30 "In14.Cu" signal "GND6")
		(32 "In15.Cu" signal "IN6")
		(34 "In16.Cu" signal "GND7")
		(2 "B.Cu" signal "BOTTOM")
		(9 "F.Adhes" user "F.Adhesive")
		(11 "B.Adhes" user "B.Adhesive")
		(13 "F.Paste" user "Package Geometry/Pastemask Top")
		(15 "B.Paste" user "Package Geometry/Pastemask Bottom")
		(5 "F.SilkS" user "Ref Des/Silkscreen Top")
		(7 "B.SilkS" user "Ref Des/Silkscreen Bottom")
		(1 "F.Mask" user "Board Geometry/Soldermask Top")
		(3 "B.Mask" user "Board Geometry/Soldermask Bottom")
		(17 "Dwgs.User" user "User.Drawings")
		(19 "Cmts.User" user "User.Comments")
		(21 "Eco1.User" user "User.Eco1")
		(23 "Eco2.User" user "User.Eco2")
		(25 "Edge.Cuts" user "Board Geometry/Outline")
		(27 "Margin" user)
		(31 "F.CrtYd" user "Package Geometry/Place Bound Top")
		(29 "B.CrtYd" user "Package Geometry/Place Bound Bottom")
		(35 "F.Fab" user "Ref Des/Assembly Top")
		(33 "B.Fab" user "Ref Des/Assembly Bottom")
	)
	(footprint ""
		(layer "B.Cu")
		(at 108.933996 -26.952448 90)
		(property "Reference" "C6097"
			(at 0 0 90)
			(layer "B.SilkS")
			(hide yes)
			(effects
				(font
					(size 1.27 1.27)
				)
				(justify mirror)
			)
		)
		(property "Value" ""
			(at 0 0 90)
			(layer "B.Fab")
			(effects
				(font
					(size 1.27 1.27)
				)
				(justify mirror)
			)
		)
		(duplicate_pad_numbers_are_jumpers no)
		(fp_line
			(start 0.7874 -0.4064)
			(end -0.7874 -0.4064)
			(stroke
				(width 0.1524)
				(type default)
			)
			(layer "B.SilkS")
		)
		(fp_line
			(start -0.7874 -0.4064)
			(end -0.7874 0.4064)
			(stroke
				(width 0.1524)
				(type default)
			)
			(layer "B.SilkS")
		)
		(fp_line
			(start 0.7874 0.4064)
			(end 0.7874 -0.4064)
			(stroke
				(width 0.1524)
				(type default)
			)
			(layer "B.SilkS")
		)
		(fp_line
			(start -0.7874 0.4064)
			(end 0.7874 0.4064)
			(stroke
				(width 0.1524)
				(type default)
			)
			(layer "B.SilkS")
		)
		(fp_line
			(start 0.67945 -0.305054)
			(end 0.12065 -0.305054)
			(stroke
				(width 0.1)
				(type default)
			)
			(layer "B.Fab")
		)
		(fp_line
			(start 0.12065 -0.305054)
			(end 0.12065 -0.2794)
			(stroke
				(width 0.1)
				(type default)
			)
			(layer "B.Fab")
		)
		(fp_line
			(start -0.12065 -0.3048)
			(end -0.67945 -0.3048)
			(stroke
				(width 0.1)
				(type default)
			)
			(layer "B.Fab")
		)
		(fp_line
			(start -0.67945 -0.3048)
			(end -0.67945 0.3048)
			(stroke
				(width 0.1)
				(type default)
			)
			(layer "B.Fab")
		)
		(fp_line
			(start 0.12065 -0.2794)
			(end -0.12065 -0.2794)
			(stroke
				(width 0.1)
				(type default)
			)
			(layer "B.Fab")
		)
		(fp_line
			(start -0.12065 -0.2794)
			(end -0.12065 -0.3048)
			(stroke
				(width 0.1)
				(type default)
			)
			(layer "B.Fab")
		)
		(fp_line
			(start 0.12065 0.2794)
			(end 0.12065 0.3048)
			(stroke
				(width 0.1)
				(type default)
			)
			(layer "B.Fab")
		)
		(fp_line
			(start -0.120396 0.2794)
			(end 0.12065 0.2794)
			(stroke
				(width 0.1)
				(type default)
			)
			(layer "B.Fab")
		)
		(fp_line
			(start 0.67945 0.3048)
			(end 0.67945 -0.305054)
			(stroke
				(width 0.1)
				(type default)
			)
			(layer "B.Fab")
		)
		(fp_line
			(start 0.12065 0.3048)
			(end 0.67945 0.3048)
			(stroke
				(width 0.1)
				(type default)
			)
			(layer "B.Fab")
		)
		(fp_line
			(start -0.120396 0.3048)
			(end -0.120396 0.2794)
			(stroke
				(width 0.1)
				(type default)
			)
			(layer "B.Fab")
		)
		(fp_line
			(start -0.67945 0.3048)
			(end -0.120396 0.3048)
			(stroke
				(width 0.1)
				(type default)
			)
			(layer "B.Fab")
		)
		(pad "1" smd circle
			(at 0.40005 0 270)
			(size 0 0)
			(layers "B.Cu" "B.Mask" "B.Paste")
			(net "P3V3_AUX_CPU0_USB2_AVDD33")
		)
		(pad "2" smd circle
			(at -0.40005 0 270)
			(size 0 0)
			(layers "B.Cu" "B.Mask" "B.Paste")
			(net "GND")
		)
	)
	(footprint ""
		(layer "B.Cu")
		(at 429.103282 -438.192672 -90)
		(property "Reference" "C7"
			(at 0 0 90)
			(layer "B.SilkS")
			(hide yes)
			(effects
				(font
					(size 1.27 1.27)
				)
				(justify mirror)
			)
		)
		(property "Value" ""
			(at 0 0 90)
			(layer "B.Fab")
			(effects
				(font
					(size 1.27 1.27)
				)
				(justify mirror)
			)
		)
		(duplicate_pad_numbers_are_jumpers no)
		(fp_line
			(start -0.7874 0.4064)
			(end 0.7874 0.4064)
			(stroke
				(width 0.1524)
				(type default)
			)
			(layer "B.SilkS")
		)
		(fp_line
			(start 0.7874 0.4064)
			(end 0.7874 -0.4064)
			(stroke
				(width 0.1524)
				(type default)
			)
			(layer "B.SilkS")
		)
		(fp_line
			(start -0.7874 -0.4064)
			(end -0.7874 0.4064)
			(stroke
				(width 0.1524)
				(type default)
			)
			(layer "B.SilkS")
		)
		(fp_line
			(start 0.7874 -0.4064)
			(end -0.7874 -0.4064)
			(stroke
				(width 0.1524)
				(type default)
			)
			(layer "B.SilkS")
		)
		(fp_line
			(start -0.67945 0.3048)
			(end -0.120396 0.3048)
			(stroke
				(width 0.1)
				(type default)
			)
			(layer "B.Fab")
		)
		(fp_line
			(start -0.120396 0.3048)
			(end -0.120396 0.2794)
			(stroke
				(width 0.1)
				(type default)
			)
			(layer "B.Fab")
		)
		(fp_line
			(start 0.12065 0.3048)
			(end 0.67945 0.3048)
			(stroke
				(width 0.1)
				(type default)
			)
			(layer "B.Fab")
		)
		(fp_line
			(start 0.67945 0.3048)
			(end 0.67945 -0.305054)
			(stroke
				(width 0.1)
				(type default)
			)
			(layer "B.Fab")
		)
		(fp_line
			(start -0.120396 0.2794)
			(end 0.12065 0.2794)
			(stroke
				(width 0.1)
				(type default)
			)
			(layer "B.Fab")
		)
		(fp_line
			(start 0.12065 0.2794)
			(end 0.12065 0.3048)
			(stroke
				(width 0.1)
				(type default)
			)
			(layer "B.Fab")
		)
		(fp_line
			(start -0.12065 -0.2794)
			(end -0.12065 -0.3048)
			(stroke
				(width 0.1)
				(type default)
			)
			(layer "B.Fab")
		)
		(fp_line
			(start 0.12065 -0.2794)
			(end -0.12065 -0.2794)
			(stroke
				(width 0.1)
				(type default)
			)
			(layer "B.Fab")
		)
		(fp_line
			(start -0.67945 -0.3048)
			(end -0.67945 0.3048)
			(stroke
				(width 0.1)
				(type default)
			)
			(layer "B.Fab")
		)
		(fp_line
			(start -0.12065 -0.3048)
			(end -0.67945 -0.3048)
			(stroke
				(width 0.1)
				(type default)
			)
			(layer "B.Fab")
		)
		(fp_line
			(start 0.12065 -0.305054)
			(end 0.12065 -0.2794)
			(stroke
				(width 0.1)
				(type default)
			)
			(layer "B.Fab")
		)
		(fp_line
			(start 0.67945 -0.305054)
			(end 0.12065 -0.305054)
			(stroke
				(width 0.1)
				(type default)
			)
			(layer "B.Fab")
		)
		(pad "1" smd circle
			(at 0.40005 0 90)
			(size 0 0)
			(layers "B.Cu" "B.Mask" "B.Paste")
			(net "GPU_3V3IO_RSVD3_ISO")
		)
		(pad "2" smd circle
			(at -0.40005 0 90)
			(size 0 0)
			(layers "B.Cu" "B.Mask" "B.Paste")
			(net "GND")
		)
	)
	(footprint ""
		(layer "B.Cu")
		(at 129.567686 -408.517344 90)
		(property "Reference" "C6733"
			(at 0 0 90)
			(layer "B.SilkS")
			(hide yes)
			(effects
				(font
					(size 1.27 1.27)
				)
				(justify mirror)
			)
		)
		(property "Value" ""
			(at 0 0 90)
			(layer "B.Fab")
			(effects
				(font
					(size 1.27 1.27)
				)
				(justify mirror)
			)
		)
		(duplicate_pad_numbers_are_jumpers no)
		(fp_line
			(start 0.299974 -0.150114)
			(end -0.299974 -0.150114)
			(stroke
				(width 0.1)
				(type default)
			)
			(layer "B.Fab")
		)
		(fp_line
			(start -0.299974 -0.150114)
			(end -0.299974 0.150114)
			(stroke
				(width 0.1)
				(type default)
			)
			(layer "B.Fab")
		)
		(fp_line
			(start 0.299974 0.150114)
			(end 0.299974 -0.150114)
			(stroke
				(width 0.1)
				(type default)
			)
			(layer "B.Fab")
		)
		(fp_line
			(start -0.299974 0.150114)
			(end 0.299974 0.150114)
			(stroke
				(width 0.1)
				(type default)
			)
			(layer "B.Fab")
		)
		(pad "1" smd rect
			(at 0.2667 0 270)
			(size 0.3048 0.381)
			(layers "B.Cu" "B.Mask" "B.Paste")
			(net "P5E_CPU1_P3_TX_BUF_C_DP<4>")
		)
		(pad "2" smd rect
			(at -0.2667 0 270)
			(size 0.3048 0.381)
			(layers "B.Cu" "B.Mask" "B.Paste")
			(net "P5E_CPU1_P3_TX_BUF_DP<4>")
		)
	)
)
